(kicad_pcb
	(version 20260206)
	(generator "pcbnew")
	(generator_version "10.0")
	(general
		(thickness 1.6)
		(legacy_teardrops no)
	)
	(paper "A4")
	(title_block
		(title "04192023_DAF0TMB3IC0_F0TG_MB_C_brd_V02_OCP.brd")
		(comment 1 "Grand Teton / footprint 2783 of 8354 (U26), pads 3671-3780 of 6102")
	)
	(layers
		(0 "F.Cu" signal "TOP")
		(4 "In1.Cu" signal "GND")
		(6 "In2.Cu" signal "IN1")
		(8 "In3.Cu" signal "GND1")
		(10 "In4.Cu" signal "IN2")
		(12 "In5.Cu" signal "GND2")
		(14 "In6.Cu" signal "IN3")
		(16 "In7.Cu" signal "GND3")
		(18 "In8.Cu" signal "VCC")
		(20 "In9.Cu" signal "VCC1")
		(22 "In10.Cu" signal "GND4")
		(24 "In11.Cu" signal "IN4")
		(26 "In12.Cu" signal "GND5")
		(28 "In13.Cu" signal "IN5")
		(30 "In14.Cu" signal "GND6")
		(32 "In15.Cu" signal "IN6")
		(34 "In16.Cu" signal "GND7")
		(2 "B.Cu" signal "BOTTOM")
		(9 "F.Adhes" user "F.Adhesive")
		(11 "B.Adhes" user "B.Adhesive")
		(13 "F.Paste" user "Package Geometry/Pastemask Top")
		(15 "B.Paste" user "Package Geometry/Pastemask Bottom")
		(5 "F.SilkS" user "Ref Des/Silkscreen Top")
		(7 "B.SilkS" user "Ref Des/Silkscreen Bottom")
		(1 "F.Mask" user "Board Geometry/Soldermask Top")
		(3 "B.Mask" user "Board Geometry/Soldermask Bottom")
		(17 "Dwgs.User" user "User.Drawings")
		(19 "Cmts.User" user "User.Comments")
		(21 "Eco1.User" user "User.Eco1")
		(23 "Eco2.User" user "User.Eco2")
		(25 "Edge.Cuts" user "Board Geometry/Outline")
		(27 "Margin" user)
		(31 "F.CrtYd" user "Package Geometry/Place Bound Top")
		(29 "B.CrtYd" user "Package Geometry/Place Bound Bottom")
		(35 "F.Fab" user "Ref Des/Assembly Top")
		(33 "B.Fab" user "Ref Des/Assembly Bottom")
	)
	(footprint ""
		(layer "F.Cu")
		(at 111.927894 -258.880356 180)
		(property "Reference" "U26"
			(at -45.05579 -61.794136 0)
			(unlocked yes)
			(layer "F.SilkS")
			(effects
				(font
					(size 0.7874 0.5842)
					(thickness 0.1524)
				)
			)
		)
		(property "Value" ""
			(at 0 0 180)
			(layer "F.Fab")
			(effects
				(font
					(size 1.27 1.27)
				)
			)
		)
		(duplicate_pad_numbers_are_jumpers no)
		(pad "CM73" smd circle
			(at 32.749998 23.040086 180)
			(size 0.450088 0.450088)
			(layers "F.Cu" "F.Mask" "F.Paste")
			(net "GND")
		)
		(pad "CM74" smd circle
			(at 33.690052 23.040086 180)
			(size 0.450088 0.450088)
			(layers "F.Cu" "F.Mask" "F.Paste")
			(net "M_A_CPU1_SB_DQ<12>")
		)
		(pad "CN1" smd circle
			(at -34.459926 23.850092 180)
			(size 0.450088 0.450088)
			(layers "F.Cu" "F.Mask" "F.Paste")
			(net "GND")
		)
		(pad "CN2" smd circle
			(at -33.519872 23.850092 180)
			(size 0.450088 0.450088)
			(layers "F.Cu" "F.Mask" "F.Paste")
			(net "M_G_CPU1_SB_DQ<14>")
		)
		(pad "CN3" smd circle
			(at -32.580072 23.850092 180)
			(size 0.450088 0.450088)
			(layers "F.Cu" "F.Mask" "F.Paste")
			(net "M_G_CPU1_SB_DQ<13>")
		)
		(pad "CN4" smd circle
			(at -31.640018 23.850092 180)
			(size 0.450088 0.450088)
			(layers "F.Cu" "F.Mask" "F.Paste")
			(net "PVDD11_S3_P1")
		)
		(pad "CN5" smd circle
			(at -30.699964 23.850092 180)
			(size 0.450088 0.450088)
			(layers "F.Cu" "F.Mask" "F.Paste")
			(net "M_K_CPU1_SB_DQ<14>")
		)
		(pad "CN6" smd circle
			(at -29.75991 23.850092 180)
			(size 0.450088 0.450088)
			(layers "F.Cu" "F.Mask" "F.Paste")
			(net "GND")
		)
		(pad "CN7" smd circle
			(at -28.82011 23.850092 180)
			(size 0.450088 0.450088)
			(layers "F.Cu" "F.Mask" "F.Paste")
			(net "M_K_CPU1_SB_DQ<13>")
		)
		(pad "CN8" smd circle
			(at -27.880056 23.850092 180)
			(size 0.450088 0.450088)
			(layers "F.Cu" "F.Mask" "F.Paste")
			(net "GND")
		)
		(pad "CN9" smd circle
			(at -26.940002 23.850092 180)
			(size 0.450088 0.450088)
			(layers "F.Cu" "F.Mask" "F.Paste")
			(net "M_L_CPU1_SB_DQ<14>")
		)
		(pad "CN10" smd circle
			(at -25.999948 23.850092 180)
			(size 0.450088 0.450088)
			(layers "F.Cu" "F.Mask" "F.Paste")
			(net "M_L_CPU1_SB_DQ<13>")
		)
		(pad "CN11" smd circle
			(at -25.059894 23.850092 180)
			(size 0.450088 0.450088)
			(layers "F.Cu" "F.Mask" "F.Paste")
			(net "PVDD11_S3_P1")
		)
		(pad "CN12" smd circle
			(at -24.120094 23.850092 180)
			(size 0.450088 0.450088)
			(layers "F.Cu" "F.Mask" "F.Paste")
			(net "M_H_CPU1_SB_DQ<14>")
		)
		(pad "CN13" smd circle
			(at -23.18004 23.850092 180)
			(size 0.450088 0.450088)
			(layers "F.Cu" "F.Mask" "F.Paste")
			(net "GND")
		)
		(pad "CN14" smd circle
			(at -22.239986 23.850092 180)
			(size 0.450088 0.450088)
			(layers "F.Cu" "F.Mask" "F.Paste")
			(net "M_H_CPU1_SB_DQ<13>")
		)
		(pad "CN15" smd circle
			(at -21.299932 23.850092 180)
			(size 0.450088 0.450088)
			(layers "F.Cu" "F.Mask" "F.Paste")
			(net "GND")
		)
		(pad "CN16" smd circle
			(at -20.359878 23.850092 180)
			(size 0.450088 0.450088)
			(layers "F.Cu" "F.Mask" "F.Paste")
			(net "M_J_CPU1_SB_DQ<14>")
		)
		(pad "CN17" smd circle
			(at -19.420078 23.850092 180)
			(size 0.450088 0.450088)
			(layers "F.Cu" "F.Mask" "F.Paste")
			(net "M_J_CPU1_SB_DQ<13>")
		)
		(pad "CN18" smd circle
			(at -18.480024 23.850092 180)
			(size 0.450088 0.450088)
			(layers "F.Cu" "F.Mask" "F.Paste")
			(net "PVDD11_S3_P1")
		)
		(pad "CN19" smd circle
			(at -17.53997 23.850092 180)
			(size 0.450088 0.450088)
			(layers "F.Cu" "F.Mask" "F.Paste")
			(net "M_I_CPU1_SB_DQ<14>")
		)
		(pad "CN20" smd circle
			(at -16.599916 23.850092 180)
			(size 0.450088 0.450088)
			(layers "F.Cu" "F.Mask" "F.Paste")
			(net "GND")
		)
		(pad "CN21" smd circle
			(at -15.660116 23.850092 180)
			(size 0.450088 0.450088)
			(layers "F.Cu" "F.Mask" "F.Paste")
			(net "M_I_CPU1_SB_DQ<13>")
		)
		(pad "CN22" smd circle
			(at -14.720062 23.850092 180)
			(size 0.450088 0.450088)
			(layers "F.Cu" "F.Mask" "F.Paste")
			(net "GND")
		)
		(pad "CN23" smd circle
			(at -13.780008 23.850092 180)
			(size 0.450088 0.450088)
			(layers "F.Cu" "F.Mask" "F.Paste")
			(net "P5E_CPU1_P2_RX_DP<15>")
		)
		(pad "CN24" smd circle
			(at -12.839954 23.850092 180)
			(size 0.450088 0.450088)
			(layers "F.Cu" "F.Mask" "F.Paste")
			(net "P5E_CPU1_P2_RX_DN<15>")
		)
		(pad "CN25" smd circle
			(at -11.8999 23.850092 180)
			(size 0.450088 0.450088)
			(layers "F.Cu" "F.Mask" "F.Paste")
			(net "GND")
		)
		(pad "CN26" smd circle
			(at -10.9601 23.850092 180)
			(size 0.450088 0.450088)
			(layers "F.Cu" "F.Mask" "F.Paste")
			(net "P5E_CPU1_P2_RX_DP<12>")
		)
		(pad "CN27" smd circle
			(at -10.020046 23.850092 180)
			(size 0.450088 0.450088)
			(layers "F.Cu" "F.Mask" "F.Paste")
			(net "P5E_CPU1_P2_RX_DN<12>")
		)
		(pad "CN28" smd circle
			(at -9.079992 23.850092 180)
			(size 0.450088 0.450088)
			(layers "F.Cu" "F.Mask" "F.Paste")
			(net "GND")
		)
		(pad "CN29" smd circle
			(at -8.139938 23.850092 180)
			(size 0.450088 0.450088)
			(layers "F.Cu" "F.Mask" "F.Paste")
			(net "P5E_CPU1_P2_RX_DP<6>")
		)
		(pad "CN30" smd circle
			(at -7.199884 23.850092 180)
			(size 0.450088 0.450088)
			(layers "F.Cu" "F.Mask" "F.Paste")
			(net "P5E_CPU1_P2_RX_DN<6>")
		)
		(pad "CN31" smd circle
			(at -6.260084 23.850092 180)
			(size 0.450088 0.450088)
			(layers "F.Cu" "F.Mask" "F.Paste")
			(net "GND")
		)
		(pad "CN32" smd circle
			(at -5.32003 23.850092 180)
			(size 0.450088 0.450088)
			(layers "F.Cu" "F.Mask" "F.Paste")
			(net "P5E_CPU1_P2_RX_DP<3>")
		)
		(pad "CN33" smd circle
			(at -4.379976 23.850092 180)
			(size 0.450088 0.450088)
			(layers "F.Cu" "F.Mask" "F.Paste")
			(net "P5E_CPU1_P2_RX_DN<3>")
		)
		(pad "CN34" smd circle
			(at -3.439922 23.850092 180)
			(size 0.450088 0.450088)
			(layers "F.Cu" "F.Mask" "F.Paste")
			(net "GND")
		)
		(pad "CN35" smd circle
			(at -2.500122 23.850092 180)
			(size 0.450088 0.450088)
			(layers "F.Cu" "F.Mask" "F.Paste")
			(net "PVDDCR_CPU1_P1")
		)
		(pad "CN36" smd circle
			(at -1.560068 23.850092 180)
			(size 0.450088 0.450088)
			(layers "F.Cu" "F.Mask" "F.Paste")
			(net "PVDDCR_CPU1_P1")
		)
		(pad "CN40" smd circle
			(at 1.260094 23.850092 180)
			(size 0.450088 0.450088)
			(layers "F.Cu" "F.Mask" "F.Paste")
			(net "PVDDCR_CPU1_P1")
		)
		(pad "CN41" smd circle
			(at 2.199894 23.850092 180)
			(size 0.450088 0.450088)
			(layers "F.Cu" "F.Mask" "F.Paste")
			(net "PVDDCR_CPU1_P1")
		)
		(pad "CN42" smd circle
			(at 3.139948 23.850092 180)
			(size 0.450088 0.450088)
			(layers "F.Cu" "F.Mask" "F.Paste")
			(net "GND")
		)
		(pad "CN43" smd circle
			(at 4.080002 23.850092 180)
			(size 0.450088 0.450088)
			(layers "F.Cu" "F.Mask" "F.Paste")
			(net "P5E_CPU1_P0_TX_DN<12>")
		)
		(pad "CN44" smd circle
			(at 5.020056 23.850092 180)
			(size 0.450088 0.450088)
			(layers "F.Cu" "F.Mask" "F.Paste")
			(net "P5E_CPU1_P0_TX_DP<12>")
		)
		(pad "CN45" smd circle
			(at 5.96011 23.850092 180)
			(size 0.450088 0.450088)
			(layers "F.Cu" "F.Mask" "F.Paste")
			(net "GND")
		)
		(pad "CN46" smd circle
			(at 6.89991 23.850092 180)
			(size 0.450088 0.450088)
			(layers "F.Cu" "F.Mask" "F.Paste")
			(net "P5E_CPU1_P0_TX_DN<9>")
		)
		(pad "CN47" smd circle
			(at 7.839964 23.850092 180)
			(size 0.450088 0.450088)
			(layers "F.Cu" "F.Mask" "F.Paste")
			(net "P5E_CPU1_P0_TX_DP<9>")
		)
		(pad "CN48" smd circle
			(at 8.780018 23.850092 180)
			(size 0.450088 0.450088)
			(layers "F.Cu" "F.Mask" "F.Paste")
			(net "GND")
		)
		(pad "CN49" smd circle
			(at 9.720072 23.850092 180)
			(size 0.450088 0.450088)
			(layers "F.Cu" "F.Mask" "F.Paste")
			(net "P5E_CPU1_P0_TX_DN<3>")
		)
		(pad "CN50" smd circle
			(at 10.659872 23.850092 180)
			(size 0.450088 0.450088)
			(layers "F.Cu" "F.Mask" "F.Paste")
			(net "P5E_CPU1_P0_TX_DP<3>")
		)
		(pad "CN51" smd circle
			(at 11.599926 23.850092 180)
			(size 0.450088 0.450088)
			(layers "F.Cu" "F.Mask" "F.Paste")
			(net "GND")
		)
		(pad "CN52" smd circle
			(at 12.53998 23.850092 180)
			(size 0.450088 0.450088)
			(layers "F.Cu" "F.Mask" "F.Paste")
			(net "P5E_CPU1_P0_TX_DN<0>")
		)
		(pad "CN53" smd circle
			(at 13.480034 23.850092 180)
			(size 0.450088 0.450088)
			(layers "F.Cu" "F.Mask" "F.Paste")
			(net "P5E_CPU1_P0_TX_DP<0>")
		)
		(pad "CN54" smd circle
			(at 14.420088 23.850092 180)
			(size 0.450088 0.450088)
			(layers "F.Cu" "F.Mask" "F.Paste")
			(net "GND")
		)
		(pad "CN55" smd circle
			(at 15.359888 23.850092 180)
			(size 0.450088 0.450088)
			(layers "F.Cu" "F.Mask" "F.Paste")
			(net "M_C_CPU1_SB_DQ<13>")
		)
		(pad "CN56" smd circle
			(at 16.299942 23.850092 180)
			(size 0.450088 0.450088)
			(layers "F.Cu" "F.Mask" "F.Paste")
			(net "GND")
		)
		(pad "CN57" smd circle
			(at 17.239996 23.850092 180)
			(size 0.450088 0.450088)
			(layers "F.Cu" "F.Mask" "F.Paste")
			(net "M_C_CPU1_SB_DQ<14>")
		)
		(pad "CN58" smd circle
			(at 18.18005 23.850092 180)
			(size 0.450088 0.450088)
			(layers "F.Cu" "F.Mask" "F.Paste")
			(net "PVDDIO_P1")
		)
		(pad "CN59" smd circle
			(at 19.120104 23.850092 180)
			(size 0.450088 0.450088)
			(layers "F.Cu" "F.Mask" "F.Paste")
			(net "M_D_CPU1_SB_DQ<13>")
		)
		(pad "CN60" smd circle
			(at 20.059904 23.850092 180)
			(size 0.450088 0.450088)
			(layers "F.Cu" "F.Mask" "F.Paste")
			(net "M_D_CPU1_SB_DQ<14>")
		)
		(pad "CN61" smd circle
			(at 20.999958 23.850092 180)
			(size 0.450088 0.450088)
			(layers "F.Cu" "F.Mask" "F.Paste")
			(net "GND")
		)
		(pad "CN62" smd circle
			(at 21.940012 23.850092 180)
			(size 0.450088 0.450088)
			(layers "F.Cu" "F.Mask" "F.Paste")
			(net "M_B_CPU1_SB_DQ<13>")
		)
		(pad "CN63" smd circle
			(at 22.880066 23.850092 180)
			(size 0.450088 0.450088)
			(layers "F.Cu" "F.Mask" "F.Paste")
			(net "GND")
		)
		(pad "CN64" smd circle
			(at 23.82012 23.850092 180)
			(size 0.450088 0.450088)
			(layers "F.Cu" "F.Mask" "F.Paste")
			(net "M_B_CPU1_SB_DQ<14>")
		)
		(pad "CN65" smd circle
			(at 24.75992 23.850092 180)
			(size 0.450088 0.450088)
			(layers "F.Cu" "F.Mask" "F.Paste")
			(net "PVDDIO_P1")
		)
		(pad "CN66" smd circle
			(at 25.699974 23.850092 180)
			(size 0.450088 0.450088)
			(layers "F.Cu" "F.Mask" "F.Paste")
			(net "M_F_CPU1_SB_DQ<13>")
		)
		(pad "CN67" smd circle
			(at 26.640028 23.850092 180)
			(size 0.450088 0.450088)
			(layers "F.Cu" "F.Mask" "F.Paste")
			(net "M_F_CPU1_SB_DQ<14>")
		)
		(pad "CN68" smd circle
			(at 27.580082 23.850092 180)
			(size 0.450088 0.450088)
			(layers "F.Cu" "F.Mask" "F.Paste")
			(net "GND")
		)
		(pad "CN69" smd circle
			(at 28.519882 23.850092 180)
			(size 0.450088 0.450088)
			(layers "F.Cu" "F.Mask" "F.Paste")
			(net "M_E_CPU1_SB_DQ<13>")
		)
		(pad "CN70" smd circle
			(at 29.459936 23.850092 180)
			(size 0.450088 0.450088)
			(layers "F.Cu" "F.Mask" "F.Paste")
			(net "GND")
		)
		(pad "CN71" smd circle
			(at 30.39999 23.850092 180)
			(size 0.450088 0.450088)
			(layers "F.Cu" "F.Mask" "F.Paste")
			(net "M_E_CPU1_SB_DQ<14>")
		)
		(pad "CN72" smd circle
			(at 31.340044 23.850092 180)
			(size 0.450088 0.450088)
			(layers "F.Cu" "F.Mask" "F.Paste")
			(net "PVDDIO_P1")
		)
		(pad "CN73" smd circle
			(at 32.280098 23.850092 180)
			(size 0.450088 0.450088)
			(layers "F.Cu" "F.Mask" "F.Paste")
			(net "M_A_CPU1_SB_DQ<13>")
		)
		(pad "CN74" smd circle
			(at 33.219898 23.850092 180)
			(size 0.450088 0.450088)
			(layers "F.Cu" "F.Mask" "F.Paste")
			(net "M_A_CPU1_SB_DQ<14>")
		)
		(pad "CN75" smd circle
			(at 34.159952 23.850092 180)
			(size 0.450088 0.450088)
			(layers "F.Cu" "F.Mask" "F.Paste")
			(net "GND")
		)
		(pad "CP2" smd circle
			(at -33.990026 24.660098 180)
			(size 0.450088 0.450088)
			(layers "F.Cu" "F.Mask" "F.Paste")
			(net "M_G_CPU1_SB_DQ<16>")
		)
		(pad "CP3" smd circle
			(at -33.049972 24.660098 180)
			(size 0.450088 0.450088)
			(layers "F.Cu" "F.Mask" "F.Paste")
			(net "GND")
		)
		(pad "CP4" smd circle
			(at -32.109918 24.660098 180)
			(size 0.450088 0.450088)
			(layers "F.Cu" "F.Mask" "F.Paste")
			(net "M_G_CPU1_SB_DQ<15>")
		)
		(pad "CP5" smd circle
			(at -31.170118 24.660098 180)
			(size 0.450088 0.450088)
			(layers "F.Cu" "F.Mask" "F.Paste")
			(net "GND")
		)
		(pad "CP6" smd circle
			(at -30.230064 24.660098 180)
			(size 0.450088 0.450088)
			(layers "F.Cu" "F.Mask" "F.Paste")
			(net "M_K_CPU1_SB_DQ<16>")
		)
		(pad "CP7" smd circle
			(at -29.29001 24.660098 180)
			(size 0.450088 0.450088)
			(layers "F.Cu" "F.Mask" "F.Paste")
			(net "M_K_CPU1_SB_DQ<15>")
		)
		(pad "CP8" smd circle
			(at -28.349956 24.660098 180)
			(size 0.450088 0.450088)
			(layers "F.Cu" "F.Mask" "F.Paste")
			(net "GND")
		)
		(pad "CP9" smd circle
			(at -27.409902 24.660098 180)
			(size 0.450088 0.450088)
			(layers "F.Cu" "F.Mask" "F.Paste")
			(net "M_L_CPU1_SB_DQ<16>")
		)
		(pad "CP10" smd circle
			(at -26.470102 24.660098 180)
			(size 0.450088 0.450088)
			(layers "F.Cu" "F.Mask" "F.Paste")
			(net "GND")
		)
		(pad "CP11" smd circle
			(at -25.530048 24.660098 180)
			(size 0.450088 0.450088)
			(layers "F.Cu" "F.Mask" "F.Paste")
			(net "M_L_CPU1_SB_DQ<15>")
		)
		(pad "CP12" smd circle
			(at -24.589994 24.660098 180)
			(size 0.450088 0.450088)
			(layers "F.Cu" "F.Mask" "F.Paste")
			(net "GND")
		)
		(pad "CP13" smd circle
			(at -23.64994 24.660098 180)
			(size 0.450088 0.450088)
			(layers "F.Cu" "F.Mask" "F.Paste")
			(net "M_H_CPU1_SB_DQ<16>")
		)
		(pad "CP14" smd circle
			(at -22.709886 24.660098 180)
			(size 0.450088 0.450088)
			(layers "F.Cu" "F.Mask" "F.Paste")
			(net "M_H_CPU1_SB_DQ<15>")
		)
		(pad "CP15" smd circle
			(at -21.770086 24.660098 180)
			(size 0.450088 0.450088)
			(layers "F.Cu" "F.Mask" "F.Paste")
			(net "GND")
		)
		(pad "CP16" smd circle
			(at -20.830032 24.660098 180)
			(size 0.450088 0.450088)
			(layers "F.Cu" "F.Mask" "F.Paste")
			(net "M_J_CPU1_SB_DQ<16>")
		)
		(pad "CP17" smd circle
			(at -19.889978 24.660098 180)
			(size 0.450088 0.450088)
			(layers "F.Cu" "F.Mask" "F.Paste")
			(net "GND")
		)
		(pad "CP18" smd circle
			(at -18.949924 24.660098 180)
			(size 0.450088 0.450088)
			(layers "F.Cu" "F.Mask" "F.Paste")
			(net "M_J_CPU1_SB_DQ<15>")
		)
		(pad "CP19" smd circle
			(at -18.010124 24.660098 180)
			(size 0.450088 0.450088)
			(layers "F.Cu" "F.Mask" "F.Paste")
			(net "GND")
		)
		(pad "CP20" smd circle
			(at -17.07007 24.660098 180)
			(size 0.450088 0.450088)
			(layers "F.Cu" "F.Mask" "F.Paste")
			(net "M_I_CPU1_SB_DQ<16>")
		)
		(pad "CP21" smd circle
			(at -16.130016 24.660098 180)
			(size 0.450088 0.450088)
			(layers "F.Cu" "F.Mask" "F.Paste")
			(net "M_I_CPU1_SB_DQ<15>")
		)
		(pad "CP22" smd circle
			(at -15.189962 24.660098 180)
			(size 0.450088 0.450088)
			(layers "F.Cu" "F.Mask" "F.Paste")
			(net "GND")
		)
		(pad "CP23" smd circle
			(at -14.249908 24.660098 180)
			(size 0.450088 0.450088)
			(layers "F.Cu" "F.Mask" "F.Paste")
			(net "PVDDCR_CPU1_P1")
		)
		(pad "CP24" smd circle
			(at -13.310108 24.660098 180)
			(size 0.450088 0.450088)
			(layers "F.Cu" "F.Mask" "F.Paste")
			(net "PVDDCR_CPU1_P1")
		)
		(pad "CP25" smd circle
			(at -12.370054 24.660098 180)
			(size 0.450088 0.450088)
			(layers "F.Cu" "F.Mask" "F.Paste")
			(net "GND")
		)
		(pad "CP26" smd circle
			(at -11.43 24.660098 180)
			(size 0.450088 0.450088)
			(layers "F.Cu" "F.Mask" "F.Paste")
			(net "PVDDCR_CPU1_P1")
		)
		(pad "CP27" smd circle
			(at -10.489946 24.660098 180)
			(size 0.450088 0.450088)
			(layers "F.Cu" "F.Mask" "F.Paste")
			(net "PVDDCR_CPU1_P1")
		)
		(pad "CP28" smd circle
			(at -9.549892 24.660098 180)
			(size 0.450088 0.450088)
			(layers "F.Cu" "F.Mask" "F.Paste")
			(net "GND")
		)
		(pad "CP29" smd circle
			(at -8.610092 24.660098 180)
			(size 0.450088 0.450088)
			(layers "F.Cu" "F.Mask" "F.Paste")
			(net "PVDDCR_CPU1_P1")
		)
		(pad "CP30" smd circle
			(at -7.670038 24.660098 180)
			(size 0.450088 0.450088)
			(layers "F.Cu" "F.Mask" "F.Paste")
			(net "PVDDCR_CPU1_P1")
		)
		(pad "CP31" smd circle
			(at -6.729984 24.660098 180)
			(size 0.450088 0.450088)
			(layers "F.Cu" "F.Mask" "F.Paste")
			(net "GND")
		)
		(pad "CP32" smd circle
			(at -5.78993 24.660098 180)
			(size 0.450088 0.450088)
			(layers "F.Cu" "F.Mask" "F.Paste")
			(net "PVDDCR_CPU1_P1")
		)
		(pad "CP33" smd circle
			(at -4.849876 24.660098 180)
			(size 0.450088 0.450088)
			(layers "F.Cu" "F.Mask" "F.Paste")
			(net "PVDDCR_CPU1_P1")
		)
		(pad "CP34" smd circle
			(at -3.910076 24.660098 180)
			(size 0.450088 0.450088)
			(layers "F.Cu" "F.Mask" "F.Paste")
			(net "GND")
		)
		(pad "CP35" smd circle
			(at -2.970022 24.660098 180)
			(size 0.450088 0.450088)
			(layers "F.Cu" "F.Mask" "F.Paste")
			(net "P5E_CPU1_P2_RX_DP<1>")
		)
		(pad "CP36" smd circle
			(at -2.029968 24.660098 180)
			(size 0.450088 0.450088)
			(layers "F.Cu" "F.Mask" "F.Paste")
			(net "P5E_CPU1_P2_RX_DN<1>")
		)
		(pad "CP37" smd circle
			(at -1.089914 24.660098 180)
			(size 0.450088 0.450088)
			(layers "F.Cu" "F.Mask" "F.Paste")
			(net "GND")
		)
	)
)
